(kicad_pcb
	(version 20241229)
	(generator "pcbnew")
	(generator_version "9.0")
	(general
		(thickness 0.761)
		(legacy_teardrops no)
	)
	(paper "A4")
	(title_block
		(title " M.2 to OCuLink adapter")
		(date "2025-07-16")
		(rev "1.0.2")
		(company "Antmicro Ltd")
		(comment 1 "www.antmicro.com")
		(comment 9 "footprint 4 of 22 (J1), pads 1-45 of 67")
	)
	(layers
		(0 "F.Cu" signal)
		(4 "In1.Cu" signal)
		(6 "In2.Cu" signal)
		(2 "B.Cu" signal)
		(9 "F.Adhes" user "F.Adhesive")
		(11 "B.Adhes" user "B.Adhesive")
		(13 "F.Paste" user)
		(15 "B.Paste" user)
		(5 "F.SilkS" user "F.Silkscreen")
		(7 "B.SilkS" user "B.Silkscreen")
		(1 "F.Mask" user)
		(3 "B.Mask" user)
		(17 "Dwgs.User" user "User.Drawings")
		(19 "Cmts.User" user "User.Comments")
		(21 "Eco1.User" user "User.Eco1")
		(23 "Eco2.User" user "User.Eco2")
		(25 "Edge.Cuts" user)
		(27 "Margin" user)
		(31 "F.CrtYd" user "F.Courtyard")
		(29 "B.CrtYd" user "B.Courtyard")
		(35 "F.Fab" user)
		(33 "B.Fab" user)
	)
	(footprint "antmicro-footprints:PCB-Edge_M.2_Key-M"
		(locked yes)
		(layer "F.Cu")
		(at 146.3 130.6)
		(property "Reference" "J1"
			(at 10.05 -5.7 0)
			(layer "F.SilkS")
			(hide yes)
			(effects
				(font
					(size 0.7 0.7)
					(thickness 0.15)
				)
				(justify left bottom)
			)
		)
		(property "Value" "PCB-Edge_M.2_Key-M"
			(at -0.075 2.25 0)
			(layer "F.Fab")
			(effects
				(font
					(size 0.7 0.7)
					(thickness 0.15)
				)
				(justify left bottom)
			)
		)
		(property "Datasheet" "https://www.amphenol-icc.com/media/wysiwyg/files/drawing/10130618.pdf"
			(at 0 0 0)
			(layer "F.Fab")
			(hide yes)
			(effects
				(font
					(size 1.27 1.27)
					(thickness 0.15)
				)
			)
		)
		(property "Description" "PCB Edge for M.2 key M"
			(at 0 0 0)
			(layer "F.Fab")
			(hide yes)
			(effects
				(font
					(size 1.27 1.27)
					(thickness 0.15)
				)
			)
		)
		(property "Author" "Antmicro"
			(at 0 0 0)
			(unlocked yes)
			(layer "F.Fab")
			(hide yes)
			(effects
				(font
					(size 1 1)
					(thickness 0.15)
				)
			)
		)
		(property "License" "Apache-2.0"
			(at 0 0 0)
			(unlocked yes)
			(layer "F.Fab")
			(hide yes)
			(effects
				(font
					(size 1 1)
					(thickness 0.15)
				)
			)
		)
		(sheetname "/")
		(sheetfile "antmicro-m2-oculink-adapter-hw.kicad_sch")
		(clearance 0)
		(attr exclude_from_pos_files exclude_from_bom)
		(pad "1" smd rect
			(at 9.1 -1.45)
			(size 0.35 2.5)
			(layers "F.Cu" "F.Mask")
			(net 1 "GND")
			(pinfunction "GND")
			(pintype "passive")
			(teardrops
				(best_length_ratio 0.5)
				(max_length 1)
				(best_width_ratio 1)
				(max_width 2)
				(curved_edges yes)
				(filter_ratio 0.9)
				(enabled no)
				(allow_two_segments yes)
				(prefer_zone_connections no)
			)
		)
		(pad "2" smd rect
			(at 8.845243 -1.7)
			(size 0.35 3)
			(layers "B.Cu" "B.Mask")
			(net 56 "Net-(C1-Pad2)")
			(pinfunction "3.3V")
			(pintype "passive")
			(teardrops
				(best_length_ratio 0.5)
				(max_length 1)
				(best_width_ratio 1)
				(max_width 2)
				(curved_edges yes)
				(filter_ratio 0.9)
				(enabled no)
				(allow_two_segments yes)
				(prefer_zone_connections no)
			)
		)
		(pad "3" smd rect
			(at 8.6 -1.45)
			(size 0.35 2.5)
			(layers "F.Cu" "F.Mask")
			(net 1 "GND")
			(pinfunction "GND")
			(pintype "passive")
			(teardrops
				(best_length_ratio 0.5)
				(max_length 1)
				(best_width_ratio 1)
				(max_width 2)
				(curved_edges yes)
				(filter_ratio 0.9)
				(enabled no)
				(allow_two_segments yes)
				(prefer_zone_connections no)
			)
		)
		(pad "4" smd rect
			(at 8.345243 -1.7)
			(size 0.35 3)
			(layers "B.Cu" "B.Mask")
			(net 56 "Net-(C1-Pad2)")
			(pinfunction "3.3V")
			(pintype "passive")
			(teardrops
				(best_length_ratio 0.5)
				(max_length 1)
				(best_width_ratio 1)
				(max_width 2)
				(curved_edges yes)
				(filter_ratio 0.9)
				(enabled no)
				(allow_two_segments yes)
				(prefer_zone_connections no)
			)
		)
		(pad "5" smd rect
			(at 8.1 -1.45)
			(size 0.35 2.5)
			(layers "F.Cu" "F.Mask")
			(net 6 "/PCIe_{x4}.RX3-")
			(pinfunction "PERn3")
			(pintype "passive")
			(teardrops
				(best_length_ratio 0.5)
				(max_length 1)
				(best_width_ratio 1)
				(max_width 2)
				(curved_edges yes)
				(filter_ratio 0.9)
				(enabled no)
				(allow_two_segments yes)
				(prefer_zone_connections no)
			)
		)
		(pad "6" smd rect
			(at 7.845243 -1.7)
			(size 0.35 3)
			(layers "B.Cu" "B.Mask")
			(net 49 "unconnected-(J1-NC-Pad6)")
			(pinfunction "NC")
			(pintype "no_connect")
			(teardrops
				(best_length_ratio 0.5)
				(max_length 1)
				(best_width_ratio 1)
				(max_width 2)
				(curved_edges yes)
				(filter_ratio 0.9)
				(enabled no)
				(allow_two_segments yes)
				(prefer_zone_connections no)
			)
		)
		(pad "7" smd rect
			(at 7.6 -1.45)
			(size 0.35 2.5)
			(layers "F.Cu" "F.Mask")
			(net 9 "/PCIe_{x4}.RX3+")
			(pinfunction "PERp3")
			(pintype "passive")
			(teardrops
				(best_length_ratio 0.5)
				(max_length 1)
				(best_width_ratio 1)
				(max_width 2)
				(curved_edges yes)
				(filter_ratio 0.9)
				(enabled no)
				(allow_two_segments yes)
				(prefer_zone_connections no)
			)
		)
		(pad "8" smd rect
			(at 7.345243 -1.7)
			(size 0.35 3)
			(layers "B.Cu" "B.Mask")
			(net 43 "unconnected-(J1-NC-Pad8)")
			(pinfunction "NC")
			(pintype "no_connect")
			(teardrops
				(best_length_ratio 0.5)
				(max_length 1)
				(best_width_ratio 1)
				(max_width 2)
				(curved_edges yes)
				(filter_ratio 0.9)
				(enabled no)
				(allow_two_segments yes)
				(prefer_zone_connections no)
			)
		)
		(pad "9" smd rect
			(at 7.1 -1.45)
			(size 0.35 2.5)
			(layers "F.Cu" "F.Mask")
			(net 1 "GND")
			(pinfunction "GND")
			(pintype "passive")
			(teardrops
				(best_length_ratio 0.5)
				(max_length 1)
				(best_width_ratio 1)
				(max_width 2)
				(curved_edges yes)
				(filter_ratio 0.9)
				(enabled no)
				(allow_two_segments yes)
				(prefer_zone_connections no)
			)
		)
		(pad "10" smd rect
			(at 6.845243 -1.7)
			(size 0.35 3)
			(layers "B.Cu" "B.Mask")
			(net 35 "unconnected-(J1-DAS-Pad10)")
			(pinfunction "DAS")
			(pintype "passive+no_connect")
			(teardrops
				(best_length_ratio 0.5)
				(max_length 1)
				(best_width_ratio 1)
				(max_width 2)
				(curved_edges yes)
				(filter_ratio 0.9)
				(enabled no)
				(allow_two_segments yes)
				(prefer_zone_connections no)
			)
		)
		(pad "11" smd rect
			(at 6.6 -1.45)
			(size 0.35 2.5)
			(layers "F.Cu" "F.Mask")
			(net 21 "/PCIe_{x4}.TX3-")
			(pinfunction "PETn3")
			(pintype "passive")
			(teardrops
				(best_length_ratio 0.5)
				(max_length 1)
				(best_width_ratio 1)
				(max_width 2)
				(curved_edges yes)
				(filter_ratio 0.9)
				(enabled no)
				(allow_two_segments yes)
				(prefer_zone_connections no)
			)
		)
		(pad "12" smd rect
			(at 6.345243 -1.7)
			(size 0.35 3)
			(layers "B.Cu" "B.Mask")
			(net 56 "Net-(C1-Pad2)")
			(pinfunction "3.3V")
			(pintype "power_in")
			(teardrops
				(best_length_ratio 0.5)
				(max_length 1)
				(best_width_ratio 1)
				(max_width 2)
				(curved_edges yes)
				(filter_ratio 0.9)
				(enabled no)
				(allow_two_segments yes)
				(prefer_zone_connections no)
			)
		)
		(pad "13" smd rect
			(at 6.1 -1.45)
			(size 0.35 2.5)
			(layers "F.Cu" "F.Mask")
			(net 2 "/PCIe_{x4}.TX3+")
			(pinfunction "PETp3")
			(pintype "passive")
			(teardrops
				(best_length_ratio 0.5)
				(max_length 1)
				(best_width_ratio 1)
				(max_width 2)
				(curved_edges yes)
				(filter_ratio 0.9)
				(enabled no)
				(allow_two_segments yes)
				(prefer_zone_connections no)
			)
		)
		(pad "14" smd rect
			(at 5.845243 -1.7)
			(size 0.35 3)
			(layers "B.Cu" "B.Mask")
			(net 56 "Net-(C1-Pad2)")
			(pinfunction "3.3V")
			(pintype "passive")
			(teardrops
				(best_length_ratio 0.5)
				(max_length 1)
				(best_width_ratio 1)
				(max_width 2)
				(curved_edges yes)
				(filter_ratio 0.9)
				(enabled no)
				(allow_two_segments yes)
				(prefer_zone_connections no)
			)
		)
		(pad "15" smd rect
			(at 5.6 -1.45)
			(size 0.35 2.5)
			(layers "F.Cu" "F.Mask")
			(net 1 "GND")
			(pinfunction "GND")
			(pintype "passive")
			(teardrops
				(best_length_ratio 0.5)
				(max_length 1)
				(best_width_ratio 1)
				(max_width 2)
				(curved_edges yes)
				(filter_ratio 0.9)
				(enabled no)
				(allow_two_segments yes)
				(prefer_zone_connections no)
			)
		)
		(pad "16" smd rect
			(at 5.345243 -1.7)
			(size 0.35 3)
			(layers "B.Cu" "B.Mask")
			(net 56 "Net-(C1-Pad2)")
			(pinfunction "3.3V")
			(pintype "passive")
			(teardrops
				(best_length_ratio 0.5)
				(max_length 1)
				(best_width_ratio 1)
				(max_width 2)
				(curved_edges yes)
				(filter_ratio 0.9)
				(enabled no)
				(allow_two_segments yes)
				(prefer_zone_connections no)
			)
		)
		(pad "17" smd rect
			(at 5.1 -1.45)
			(size 0.35 2.5)
			(layers "F.Cu" "F.Mask")
			(net 14 "/PCIe_{x4}.RX2-")
			(pinfunction "PERn2")
			(pintype "passive")
			(teardrops
				(best_length_ratio 0.5)
				(max_length 1)
				(best_width_ratio 1)
				(max_width 2)
				(curved_edges yes)
				(filter_ratio 0.9)
				(enabled no)
				(allow_two_segments yes)
				(prefer_zone_connections no)
			)
		)
		(pad "18" smd rect
			(at 4.845243 -1.7)
			(size 0.35 3)
			(layers "B.Cu" "B.Mask")
			(net 56 "Net-(C1-Pad2)")
			(pinfunction "3.3V")
			(pintype "passive")
			(teardrops
				(best_length_ratio 0.5)
				(max_length 1)
				(best_width_ratio 1)
				(max_width 2)
				(curved_edges yes)
				(filter_ratio 0.9)
				(enabled no)
				(allow_two_segments yes)
				(prefer_zone_connections no)
			)
		)
		(pad "19" smd rect
			(at 4.6 -1.45)
			(size 0.35 2.5)
			(layers "F.Cu" "F.Mask")
			(net 4 "/PCIe_{x4}.RX2+")
			(pinfunction "PERp2")
			(pintype "passive")
			(teardrops
				(best_length_ratio 0.5)
				(max_length 1)
				(best_width_ratio 1)
				(max_width 2)
				(curved_edges yes)
				(filter_ratio 0.9)
				(enabled no)
				(allow_two_segments yes)
				(prefer_zone_connections no)
			)
		)
		(pad "20" smd rect
			(at 4.345243 -1.7)
			(size 0.35 3)
			(layers "B.Cu" "B.Mask")
			(net 42 "unconnected-(J1-NC-Pad20)")
			(pinfunction "NC")
			(pintype "no_connect")
			(teardrops
				(best_length_ratio 0.5)
				(max_length 1)
				(best_width_ratio 1)
				(max_width 2)
				(curved_edges yes)
				(filter_ratio 0.9)
				(enabled no)
				(allow_two_segments yes)
				(prefer_zone_connections no)
			)
		)
		(pad "21" smd rect
			(at 4.1 -1.45)
			(size 0.35 2.5)
			(layers "F.Cu" "F.Mask")
			(net 1 "GND")
			(pinfunction "GND")
			(pintype "passive")
			(teardrops
				(best_length_ratio 0.5)
				(max_length 1)
				(best_width_ratio 1)
				(max_width 2)
				(curved_edges yes)
				(filter_ratio 0.9)
				(enabled no)
				(allow_two_segments yes)
				(prefer_zone_connections no)
			)
		)
		(pad "22" smd rect
			(at 3.845243 -1.7)
			(size 0.35 3)
			(layers "B.Cu" "B.Mask")
			(net 18 "unconnected-(J1-NC-Pad22)")
			(pinfunction "NC")
			(pintype "no_connect")
			(teardrops
				(best_length_ratio 0.5)
				(max_length 1)
				(best_width_ratio 1)
				(max_width 2)
				(curved_edges yes)
				(filter_ratio 0.9)
				(enabled no)
				(allow_two_segments yes)
				(prefer_zone_connections no)
			)
		)
		(pad "23" smd rect
			(at 3.6 -1.45)
			(size 0.35 2.5)
			(layers "F.Cu" "F.Mask")
			(net 10 "/PCIe_{x4}.TX2-")
			(pinfunction "PETn2")
			(pintype "passive")
			(teardrops
				(best_length_ratio 0.5)
				(max_length 1)
				(best_width_ratio 1)
				(max_width 2)
				(curved_edges yes)
				(filter_ratio 0.9)
				(enabled no)
				(allow_two_segments yes)
				(prefer_zone_connections no)
			)
		)
		(pad "24" smd rect
			(at 3.345243 -1.7)
			(size 0.35 3)
			(layers "B.Cu" "B.Mask")
			(net 34 "unconnected-(J1-NC-Pad24)")
			(pinfunction "NC")
			(pintype "no_connect")
			(teardrops
				(best_length_ratio 0.5)
				(max_length 1)
				(best_width_ratio 1)
				(max_width 2)
				(curved_edges yes)
				(filter_ratio 0.9)
				(enabled no)
				(allow_two_segments yes)
				(prefer_zone_connections no)
			)
		)
		(pad "25" smd rect
			(at 3.1 -1.45)
			(size 0.35 2.5)
			(layers "F.Cu" "F.Mask")
			(net 5 "/PCIe_{x4}.TX2+")
			(pinfunction "PETp2")
			(pintype "passive")
			(teardrops
				(best_length_ratio 0.5)
				(max_length 1)
				(best_width_ratio 1)
				(max_width 2)
				(curved_edges yes)
				(filter_ratio 0.9)
				(enabled no)
				(allow_two_segments yes)
				(prefer_zone_connections no)
			)
		)
		(pad "26" smd rect
			(at 2.845243 -1.7)
			(size 0.35 3)
			(layers "B.Cu" "B.Mask")
			(net 45 "unconnected-(J1-NC-Pad26)")
			(pinfunction "NC")
			(pintype "no_connect")
			(teardrops
				(best_length_ratio 0.5)
				(max_length 1)
				(best_width_ratio 1)
				(max_width 2)
				(curved_edges yes)
				(filter_ratio 0.9)
				(enabled no)
				(allow_two_segments yes)
				(prefer_zone_connections no)
			)
		)
		(pad "27" smd rect
			(at 2.6 -1.45)
			(size 0.35 2.5)
			(layers "F.Cu" "F.Mask")
			(net 1 "GND")
			(pinfunction "GND")
			(pintype "passive")
			(teardrops
				(best_length_ratio 0.5)
				(max_length 1)
				(best_width_ratio 1)
				(max_width 2)
				(curved_edges yes)
				(filter_ratio 0.9)
				(enabled no)
				(allow_two_segments yes)
				(prefer_zone_connections no)
			)
		)
		(pad "28" smd rect
			(at 2.345243 -1.7)
			(size 0.35 3)
			(layers "B.Cu" "B.Mask")
			(net 48 "unconnected-(J1-NC-Pad28)")
			(pinfunction "NC")
			(pintype "no_connect")
			(teardrops
				(best_length_ratio 0.5)
				(max_length 1)
				(best_width_ratio 1)
				(max_width 2)
				(curved_edges yes)
				(filter_ratio 0.9)
				(enabled no)
				(allow_two_segments yes)
				(prefer_zone_connections no)
			)
		)
		(pad "29" smd rect
			(at 2.1 -1.45)
			(size 0.35 2.5)
			(layers "F.Cu" "F.Mask")
			(net 27 "/PCIe_{x4}.RX1-")
			(pinfunction "PERn1")
			(pintype "passive")
			(teardrops
				(best_length_ratio 0.5)
				(max_length 1)
				(best_width_ratio 1)
				(max_width 2)
				(curved_edges yes)
				(filter_ratio 0.9)
				(enabled no)
				(allow_two_segments yes)
				(prefer_zone_connections no)
			)
		)
		(pad "30" smd rect
			(at 1.845243 -1.7)
			(size 0.35 3)
			(layers "B.Cu" "B.Mask")
			(net 19 "unconnected-(J1-NC-Pad30)")
			(pinfunction "NC")
			(pintype "no_connect")
			(teardrops
				(best_length_ratio 0.5)
				(max_length 1)
				(best_width_ratio 1)
				(max_width 2)
				(curved_edges yes)
				(filter_ratio 0.9)
				(enabled no)
				(allow_two_segments yes)
				(prefer_zone_connections no)
			)
		)
		(pad "31" smd rect
			(at 1.6 -1.45)
			(size 0.35 2.5)
			(layers "F.Cu" "F.Mask")
			(net 16 "/PCIe_{x4}.RX1+")
			(pinfunction "PERp1")
			(pintype "passive")
			(teardrops
				(best_length_ratio 0.5)
				(max_length 1)
				(best_width_ratio 1)
				(max_width 2)
				(curved_edges yes)
				(filter_ratio 0.9)
				(enabled no)
				(allow_two_segments yes)
				(prefer_zone_connections no)
			)
		)
		(pad "32" smd rect
			(at 1.345243 -1.7)
			(size 0.35 3)
			(layers "B.Cu" "B.Mask")
			(net 31 "unconnected-(J1-NC-Pad32)")
			(pinfunction "NC")
			(pintype "no_connect")
			(teardrops
				(best_length_ratio 0.5)
				(max_length 1)
				(best_width_ratio 1)
				(max_width 2)
				(curved_edges yes)
				(filter_ratio 0.9)
				(enabled no)
				(allow_two_segments yes)
				(prefer_zone_connections no)
			)
		)
		(pad "33" smd rect
			(at 1.1 -1.45)
			(size 0.35 2.5)
			(layers "F.Cu" "F.Mask")
			(net 1 "GND")
			(pinfunction "GND")
			(pintype "passive")
			(teardrops
				(best_length_ratio 0.5)
				(max_length 1)
				(best_width_ratio 1)
				(max_width 2)
				(curved_edges yes)
				(filter_ratio 0.9)
				(enabled no)
				(allow_two_segments yes)
				(prefer_zone_connections no)
			)
		)
		(pad "34" smd rect
			(at 0.845243 -1.7)
			(size 0.35 3)
			(layers "B.Cu" "B.Mask")
			(net 44 "unconnected-(J1-NC-Pad34)")
			(pinfunction "NC")
			(pintype "no_connect")
			(teardrops
				(best_length_ratio 0.5)
				(max_length 1)
				(best_width_ratio 1)
				(max_width 2)
				(curved_edges yes)
				(filter_ratio 0.9)
				(enabled no)
				(allow_two_segments yes)
				(prefer_zone_connections no)
			)
		)
		(pad "35" smd rect
			(at 0.6 -1.45)
			(size 0.35 2.5)
			(layers "F.Cu" "F.Mask")
			(net 8 "/PCIe_{x4}.TX1-")
			(pinfunction "PETn1")
			(pintype "passive")
			(teardrops
				(best_length_ratio 0.5)
				(max_length 1)
				(best_width_ratio 1)
				(max_width 2)
				(curved_edges yes)
				(filter_ratio 0.9)
				(enabled no)
				(allow_two_segments yes)
				(prefer_zone_connections no)
			)
		)
		(pad "36" smd rect
			(at 0.345243 -1.7)
			(size 0.35 3)
			(layers "B.Cu" "B.Mask")
			(net 29 "unconnected-(J1-NC-Pad36)")
			(pinfunction "NC")
			(pintype "no_connect")
			(teardrops
				(best_length_ratio 0.5)
				(max_length 1)
				(best_width_ratio 1)
				(max_width 2)
				(curved_edges yes)
				(filter_ratio 0.9)
				(enabled no)
				(allow_two_segments yes)
				(prefer_zone_connections no)
			)
		)
		(pad "37" smd rect
			(at 0.1 -1.45)
			(size 0.35 2.5)
			(layers "F.Cu" "F.Mask")
			(net 3 "/PCIe_{x4}.TX1+")
			(pinfunction "PETp1")
			(pintype "passive")
			(teardrops
				(best_length_ratio 0.5)
				(max_length 1)
				(best_width_ratio 1)
				(max_width 2)
				(curved_edges yes)
				(filter_ratio 0.9)
				(enabled no)
				(allow_two_segments yes)
				(prefer_zone_connections no)
			)
		)
		(pad "38" smd rect
			(at -0.154757 -1.7)
			(size 0.35 3)
			(layers "B.Cu" "B.Mask")
			(net 32 "unconnected-(J1-DEVSLP-Pad38)")
			(pinfunction "DEVSLP")
			(pintype "passive+no_connect")
			(teardrops
				(best_length_ratio 0.5)
				(max_length 1)
				(best_width_ratio 1)
				(max_width 2)
				(curved_edges yes)
				(filter_ratio 0.9)
				(enabled no)
				(allow_two_segments yes)
				(prefer_zone_connections no)
			)
		)
		(pad "39" smd rect
			(at -0.4 -1.45)
			(size 0.35 2.5)
			(layers "F.Cu" "F.Mask")
			(net 1 "GND")
			(pinfunction "GND")
			(pintype "passive")
			(teardrops
				(best_length_ratio 0.5)
				(max_length 1)
				(best_width_ratio 1)
				(max_width 2)
				(curved_edges yes)
				(filter_ratio 0.9)
				(enabled no)
				(allow_two_segments yes)
				(prefer_zone_connections no)
			)
		)
		(pad "40" smd rect
			(at -0.654757 -1.7)
			(size 0.35 3)
			(layers "B.Cu" "B.Mask")
			(net 28 "unconnected-(J1-NC-Pad40)")
			(pinfunction "NC")
			(pintype "no_connect")
			(teardrops
				(best_length_ratio 0.5)
				(max_length 1)
				(best_width_ratio 1)
				(max_width 2)
				(curved_edges yes)
				(filter_ratio 0.9)
				(enabled no)
				(allow_two_segments yes)
				(prefer_zone_connections no)
			)
		)
		(pad "41" smd rect
			(at -0.9 -1.45)
			(size 0.35 2.5)
			(layers "F.Cu" "F.Mask")
			(net 7 "/PCIe_{x4}.RX0-")
			(pinfunction "PERn0")
			(pintype "passive")
			(teardrops
				(best_length_ratio 0.5)
				(max_length 1)
				(best_width_ratio 1)
				(max_width 2)
				(curved_edges yes)
				(filter_ratio 0.9)
				(enabled no)
				(allow_two_segments yes)
				(prefer_zone_connections no)
			)
		)
		(pad "42" smd rect
			(at -1.154757 -1.7)
			(size 0.35 3)
			(layers "B.Cu" "B.Mask")
			(net 46 "unconnected-(J1-NC-Pad42)")
			(pinfunction "NC")
			(pintype "no_connect")
			(teardrops
				(best_length_ratio 0.5)
				(max_length 1)
				(best_width_ratio 1)
				(max_width 2)
				(curved_edges yes)
				(filter_ratio 0.9)
				(enabled no)
				(allow_two_segments yes)
				(prefer_zone_connections no)
			)
		)
		(pad "43" smd rect
			(at -1.4 -1.45)
			(size 0.35 2.5)
			(layers "F.Cu" "F.Mask")
			(net 26 "/PCIe_{x4}.RX0+")
			(pinfunction "PERp0")
			(pintype "passive")
			(teardrops
				(best_length_ratio 0.5)
				(max_length 1)
				(best_width_ratio 1)
				(max_width 2)
				(curved_edges yes)
				(filter_ratio 0.9)
				(enabled no)
				(allow_two_segments yes)
				(prefer_zone_connections no)
			)
		)
		(pad "44" smd rect
			(at -1.654757 -1.7)
			(size 0.35 3)
			(layers "B.Cu" "B.Mask")
			(net 40 "unconnected-(J1-NC-Pad44)")
			(pinfunction "NC")
			(pintype "no_connect")
			(teardrops
				(best_length_ratio 0.5)
				(max_length 1)
				(best_width_ratio 1)
				(max_width 2)
				(curved_edges yes)
				(filter_ratio 0.9)
				(enabled no)
				(allow_two_segments yes)
				(prefer_zone_connections no)
			)
		)
		(pad "45" smd rect
			(at -1.9 -1.45)
			(size 0.35 2.5)
			(layers "F.Cu" "F.Mask")
			(net 1 "GND")
			(pinfunction "GND")
			(pintype "passive")
			(teardrops
				(best_length_ratio 0.5)
				(max_length 1)
				(best_width_ratio 1)
				(max_width 2)
				(curved_edges yes)
				(filter_ratio 0.9)
				(enabled no)
				(allow_two_segments yes)
				(prefer_zone_connections no)
			)
		)
	)
)
